FILE_TYPE = CONNECTIVITY;
{Allegro Design Entry HDL 17.2-2016 S081 (4005846) 1/11/2022}
"PAGE_NUMBER" = 53;
0"NC";
1"M_C_CPU1_SA_CA<6:0>";
2"M_C_CPU1_SA_CS_N<3:0>";
3"M_C_CPU1_SA_DQS_DN<9:0>";
4"M_C_CPU1_SA_DQS_DP<9:0>";
5"M_C_CPU1_SB_CA<6:0>";
6"M_C_CPU1_SB_CS_N<3:0>";
7"M_C_CPU1_SB_DQS_DN<9:0>";
8"M_C_CPU1_SB_DQS_DP<9:0>";
9"M_C_CPU1_SB_CB<7:0>";
10"M_C_CPU1_SB_DQ<31:0>";
11"M_C_CPU1_SA_CB<7:0>";
12"M_C_CPU1_SA_DQ<31:0>";
13"M_C_CPU1_CLK_DP<1:0>";
14"M_C_CPU1_CLK_DN<1:0>";
15"M_C_CPU1_CLK_DN<1>";
16"M_C_CPU1_CLK_DN<0>";
17"M_C_CPU1_CLK_DP<1>";
18"M_C_CPU1_CLK_DP<0>";
19"M_C_CPU1_SA_DQ<31>";
20"M_C_CPU1_SA_DQ<30>";
21"M_C_CPU1_SA_DQ<29>";
22"M_C_CPU1_SA_DQ<28>";
23"M_C_CPU1_SA_DQ<27>";
24"M_C_CPU1_SA_DQ<26>";
25"M_C_CPU1_SA_DQ<25>";
26"M_C_CPU1_SA_DQ<24>";
27"M_C_CPU1_SA_DQ<23>";
28"M_C_CPU1_SA_DQ<22>";
29"M_C_CPU1_SA_DQ<21>";
30"M_C_CPU1_SA_DQ<20>";
31"M_C_CPU1_SA_DQ<19>";
32"M_C_CPU1_SA_DQ<18>";
33"M_C_CPU1_SA_DQ<17>";
34"M_C_CPU1_SA_DQ<16>";
35"M_C_CPU1_SA_DQ<15>";
36"M_C_CPU1_SA_DQ<14>";
37"M_C_CPU1_SA_DQ<13>";
38"M_C_CPU1_SA_DQ<12>";
39"M_C_CPU1_SA_DQ<11>";
40"M_C_CPU1_SA_DQ<10>";
41"M_C_CPU1_SA_DQ<9>";
42"M_C_CPU1_SA_DQ<8>";
43"M_C_CPU1_SA_DQ<7>";
44"M_C_CPU1_SA_DQ<6>";
45"M_C_CPU1_SA_DQ<5>";
46"M_C_CPU1_SA_DQ<4>";
47"M_C_CPU1_SA_DQ<3>";
48"M_C_CPU1_SA_DQ<2>";
49"M_C_CPU1_SA_DQ<1>";
50"M_C_CPU1_SA_DQ<0>";
51"M_C_CPU1_SA_CB<7>";
52"M_C_CPU1_SA_CB<6>";
53"M_C_CPU1_SA_CB<5>";
54"M_C_CPU1_SA_CB<4>";
55"M_C_CPU1_SA_CB<3>";
56"M_C_CPU1_SA_CB<2>";
57"M_C_CPU1_SA_CB<1>";
58"M_C_CPU1_SA_CB<0>";
59"M_C_CPU1_SB_DQ<31>";
60"M_C_CPU1_SB_DQ<30>";
61"M_C_CPU1_SB_DQ<29>";
62"M_C_CPU1_SB_DQ<28>";
63"M_C_CPU1_SB_DQ<27>";
64"M_C_CPU1_SB_DQ<26>";
65"M_C_CPU1_SB_DQ<25>";
66"M_C_CPU1_SB_DQ<24>";
67"M_C_CPU1_SB_DQ<23>";
68"M_C_CPU1_SB_DQ<22>";
69"M_C_CPU1_SB_DQ<21>";
70"M_C_CPU1_SB_DQ<20>";
71"M_C_CPU1_SB_DQ<19>";
72"M_C_CPU1_SB_DQ<18>";
73"M_C_CPU1_SB_DQ<17>";
74"M_C_CPU1_SB_DQ<16>";
75"M_C_CPU1_SB_DQ<15>";
76"M_C_CPU1_SB_DQ<14>";
77"M_C_CPU1_SB_DQ<13>";
78"M_C_CPU1_SB_DQ<12>";
79"M_C_CPU1_SB_DQ<11>";
80"M_C_CPU1_SB_DQ<10>";
81"M_C_CPU1_SB_DQ<9>";
82"M_C_CPU1_SB_DQ<8>";
83"M_C_CPU1_SB_DQ<7>";
84"M_C_CPU1_SB_DQ<6>";
85"M_C_CPU1_SB_DQ<5>";
86"M_C_CPU1_SB_DQ<4>";
87"M_C_CPU1_SB_DQ<3>";
88"M_C_CPU1_SB_DQ<2>";
89"M_C_CPU1_SB_DQ<1>";
90"M_C_CPU1_SB_DQ<0>";
91"M_C_CPU1_SB_CB<7>";
92"M_C_CPU1_SB_CB<6>";
93"M_C_CPU1_SB_CB<5>";
94"M_C_CPU1_SB_CB<4>";
95"M_C_CPU1_SB_CB<3>";
96"M_C_CPU1_SB_CB<2>";
97"M_C_CPU1_SB_CB<1>";
98"M_C_CPU1_SB_CB<0>";
99"M_C_CPU1_SB_PAR";
100"M_C_CPU1_SB_DQS_DP<0>";
101"M_C_CPU1_SB_DQS_DP<1>";
102"M_C_CPU1_SB_DQS_DP<2>";
103"M_C_CPU1_SB_DQS_DP<3>";
104"M_C_CPU1_SB_DQS_DP<4>";
105"M_C_CPU1_SB_DQS_DP<5>";
106"M_C_CPU1_SB_DQS_DP<6>";
107"M_C_CPU1_SB_DQS_DP<7>";
108"M_C_CPU1_SB_DQS_DP<8>";
109"M_C_CPU1_SB_DQS_DP<9>";
110"M_C_CPU1_SB_DQS_DN<0>";
111"M_C_CPU1_SB_DQS_DN<1>";
112"M_C_CPU1_SB_DQS_DN<2>";
113"M_C_CPU1_SB_DQS_DN<3>";
114"M_C_CPU1_SB_DQS_DN<4>";
115"M_C_CPU1_SB_DQS_DN<5>";
116"M_C_CPU1_SB_DQS_DN<6>";
117"M_C_CPU1_SB_DQS_DN<7>";
118"M_C_CPU1_SB_DQS_DN<8>";
119"M_C_CPU1_SB_DQS_DN<9>";
120"M_C_CPU1_SB_CS_N<0>";
121"M_C_CPU1_SB_CS_N<1>";
122"M_C_CPU1_SB_CS_N<2>";
123"M_C_CPU1_SB_CS_N<3>";
124"M_C_CPU1_SB_CA<0>";
125"M_C_CPU1_SB_CA<1>";
126"M_C_CPU1_SB_CA<2>";
127"M_C_CPU1_SB_CA<3>";
128"M_C_CPU1_SB_CA<4>";
129"M_C_CPU1_SB_CA<5>";
130"M_C_CPU1_SB_CA<6>";
131"M_C_CPU1_SA_PAR";
132"M_C_CPU1_SA_DQS_DP<0>";
133"M_C_CPU1_SA_DQS_DP<1>";
134"M_C_CPU1_SA_DQS_DP<2>";
135"M_C_CPU1_SA_DQS_DP<3>";
136"M_C_CPU1_SA_DQS_DP<4>";
137"M_C_CPU1_SA_DQS_DP<5>";
138"M_C_CPU1_SA_DQS_DP<6>";
139"M_C_CPU1_SA_DQS_DP<7>";
140"M_C_CPU1_SA_DQS_DP<8>";
141"M_C_CPU1_SA_DQS_DP<9>";
142"M_C_CPU1_SA_DQS_DN<0>";
143"M_C_CPU1_SA_DQS_DN<1>";
144"M_C_CPU1_SA_DQS_DN<2>";
145"M_C_CPU1_SA_DQS_DN<3>";
146"M_C_CPU1_SA_DQS_DN<4>";
147"M_C_CPU1_SA_DQS_DN<5>";
148"M_C_CPU1_SA_DQS_DN<6>";
149"M_C_CPU1_SA_DQS_DN<7>";
150"M_C_CPU1_SA_DQS_DN<8>";
151"M_C_CPU1_SA_DQS_DN<9>";
152"M_C_CPU1_SA_CS_N<0>";
153"M_C_CPU1_SA_CS_N<1>";
154"M_C_CPU1_SA_CS_N<2>";
155"M_C_CPU1_SA_CS_N<3>";
156"M_C_CPU1_SA_CA<0>";
157"M_C_CPU1_SA_CA<1>";
158"M_C_CPU1_SA_CA<2>";
159"M_C_CPU1_SA_CA<3>";
160"M_C_CPU1_SA_CA<4>";
161"M_C_CPU1_SA_CA<5>";
162"M_C_CPU1_SA_CA<6>";
163"M_C_CPU1_SB_RSP<0>";
164"M_C_CPU1_SB_RSP<1>";
165"M_C_CPU1_SA_RSP<0>";
166"M_C_CPU1_SA_RSP<1>";
167"M_C_CPU1_ALERT_N";
%"TAP"
"1","(-675,50)","2","standard","I10";
;
CDS_LIB"standard"
BODY_TYPE"PLUMBING"
HDL_TAP"TRUE";
"B \NAC \NWC"9;
"S \NAC"
BN"1"97;
%"TAP"
"1","(2750,350)","0","standard","I100";
;
CDS_LIB"standard"
BODY_TYPE"PLUMBING"
HDL_TAP"TRUE";
"B \NAC \NWC"6;
"S \NAC"
BN"3"123;
%"TAP"
"1","(2750,550)","0","standard","I101";
;
CDS_LIB"standard"
BODY_TYPE"PLUMBING"
HDL_TAP"TRUE";
"B \NAC \NWC"2;
"S \NAC"
BN"1"153;
%"TAP"
"1","(2750,500)","0","standard","I102";
;
CDS_LIB"standard"
BODY_TYPE"PLUMBING"
HDL_TAP"TRUE";
"B \NAC \NWC"2;
"S \NAC"
BN"0"152;
%"TAP"
"1","(2750,600)","0","standard","I103";
;
CDS_LIB"standard"
BODY_TYPE"PLUMBING"
HDL_TAP"TRUE";
"B \NAC \NWC"2;
"S \NAC"
BN"2"154;
%"TAP"
"1","(2750,650)","0","standard","I104";
;
CDS_LIB"standard"
BODY_TYPE"PLUMBING"
HDL_TAP"TRUE";
"B \NAC \NWC"2;
"S \NAC"
BN"3"155;
%"TAP"
"1","(2750,950)","0","standard","I105";
;
CDS_LIB"standard"
BODY_TYPE"PLUMBING"
HDL_TAP"TRUE";
"B \NAC \NWC"5;
"S \NAC"
BN"2"126;
%"TAP"
"1","(2750,850)","0","standard","I106";
;
CDS_LIB"standard"
BODY_TYPE"PLUMBING"
HDL_TAP"TRUE";
"B \NAC \NWC"5;
"S \NAC"
BN"0"124;
%"TAP"
"1","(2750,900)","0","standard","I107";
;
CDS_LIB"standard"
BODY_TYPE"PLUMBING"
HDL_TAP"TRUE";
"B \NAC \NWC"5;
"S \NAC"
BN"1"125;
%"TAP"
"1","(2750,1050)","0","standard","I108";
;
CDS_LIB"standard"
BODY_TYPE"PLUMBING"
HDL_TAP"TRUE";
"B \NAC \NWC"5;
"S \NAC"
BN"4"128;
%"TAP"
"1","(2750,1000)","0","standard","I109";
;
CDS_LIB"standard"
BODY_TYPE"PLUMBING"
HDL_TAP"TRUE";
"B \NAC \NWC"5;
"S \NAC"
BN"3"127;
%"TAP"
"1","(-675,200)","2","standard","I11";
;
CDS_LIB"standard"
BODY_TYPE"PLUMBING"
HDL_TAP"TRUE";
"B \NAC \NWC"9;
"S \NAC"
BN"4"94;
%"TAP"
"1","(2750,1150)","0","standard","I110";
;
CDS_LIB"standard"
BODY_TYPE"PLUMBING"
HDL_TAP"TRUE";
"B \NAC \NWC"5;
"S \NAC"
BN"6"130;
%"TAP"
"1","(2750,1100)","0","standard","I111";
;
CDS_LIB"standard"
BODY_TYPE"PLUMBING"
HDL_TAP"TRUE";
"B \NAC \NWC"5;
"S \NAC"
BN"5"129;
%"TAP"
"1","(2750,1400)","0","standard","I112";
;
CDS_LIB"standard"
BODY_TYPE"PLUMBING"
HDL_TAP"TRUE";
"B \NAC \NWC"1;
"S \NAC"
BN"1"157;
%"TAP"
"1","(2750,1350)","0","standard","I113";
;
CDS_LIB"standard"
BODY_TYPE"PLUMBING"
HDL_TAP"TRUE";
"B \NAC \NWC"1;
"S \NAC"
BN"0"156;
%"TAP"
"1","(2750,1450)","0","standard","I114";
;
CDS_LIB"standard"
BODY_TYPE"PLUMBING"
HDL_TAP"TRUE";
"B \NAC \NWC"1;
"S \NAC"
BN"2"158;
%"TAP"
"1","(2750,1550)","0","standard","I115";
;
CDS_LIB"standard"
BODY_TYPE"PLUMBING"
HDL_TAP"TRUE";
"B \NAC \NWC"1;
"S \NAC"
BN"4"160;
%"TAP"
"1","(2750,1600)","0","standard","I116";
;
CDS_LIB"standard"
BODY_TYPE"PLUMBING"
HDL_TAP"TRUE";
"B \NAC \NWC"1;
"S \NAC"
BN"5"161;
%"TAP"
"1","(2750,1500)","0","standard","I117";
;
CDS_LIB"standard"
BODY_TYPE"PLUMBING"
HDL_TAP"TRUE";
"B \NAC \NWC"1;
"S \NAC"
BN"3"159;
%"TAP"
"1","(2750,1650)","0","standard","I118";
;
CDS_LIB"standard"
BODY_TYPE"PLUMBING"
HDL_TAP"TRUE";
"B \NAC \NWC"1;
"S \NAC"
BN"6"162;
%"TAP"
"1","(2750,1800)","0","standard","I119";
;
CDS_LIB"standard"
BODY_TYPE"PLUMBING"
HDL_TAP"TRUE";
"B \NAC \NWC"7;
"S \NAC"
BN"0"110;
%"TAP"
"1","(-675,250)","2","standard","I12";
;
CDS_LIB"standard"
BODY_TYPE"PLUMBING"
HDL_TAP"TRUE";
"B \NAC \NWC"9;
"S \NAC"
BN"5"93;
%"TAP"
"1","(2750,1850)","0","standard","I120";
;
CDS_LIB"standard"
BODY_TYPE"PLUMBING"
HDL_TAP"TRUE";
"B \NAC \NWC"7;
"S \NAC"
BN"1"111;
%"TAP"
"1","(2750,1900)","0","standard","I121";
;
CDS_LIB"standard"
BODY_TYPE"PLUMBING"
HDL_TAP"TRUE";
"B \NAC \NWC"7;
"S \NAC"
BN"2"112;
%"TAP"
"1","(2750,1950)","0","standard","I122";
;
CDS_LIB"standard"
BODY_TYPE"PLUMBING"
HDL_TAP"TRUE";
"B \NAC \NWC"7;
"S \NAC"
BN"3"113;
%"TAP"
"1","(2750,2100)","0","standard","I123";
;
CDS_LIB"standard"
BODY_TYPE"PLUMBING"
HDL_TAP"TRUE";
"B \NAC \NWC"7;
"S \NAC"
BN"6"116;
%"TAP"
"1","(2750,2050)","0","standard","I124";
;
CDS_LIB"standard"
BODY_TYPE"PLUMBING"
HDL_TAP"TRUE";
"B \NAC \NWC"7;
"S \NAC"
BN"5"115;
%"TAP"
"1","(2750,2000)","0","standard","I125";
;
CDS_LIB"standard"
BODY_TYPE"PLUMBING"
HDL_TAP"TRUE";
"B \NAC \NWC"7;
"S \NAC"
BN"4"114;
%"TAP"
"1","(2750,2200)","0","standard","I126";
;
CDS_LIB"standard"
BODY_TYPE"PLUMBING"
HDL_TAP"TRUE";
"B \NAC \NWC"7;
"S \NAC"
BN"8"118;
%"TAP"
"1","(2750,2150)","0","standard","I127";
;
CDS_LIB"standard"
BODY_TYPE"PLUMBING"
HDL_TAP"TRUE";
"B \NAC \NWC"7;
"S \NAC"
BN"7"117;
%"TAP"
"1","(2750,2250)","0","standard","I128";
;
CDS_LIB"standard"
BODY_TYPE"PLUMBING"
HDL_TAP"TRUE";
"B \NAC \NWC"7;
"S \NAC"
BN"9"119;
%"TAP"
"1","(2750,2350)","0","standard","I129";
;
CDS_LIB"standard"
BODY_TYPE"PLUMBING"
HDL_TAP"TRUE";
"B \NAC \NWC"8;
"S \NAC"
BN"0"100;
%"TAP"
"1","(-675,300)","2","standard","I13";
;
CDS_LIB"standard"
BODY_TYPE"PLUMBING"
HDL_TAP"TRUE";
"B \NAC \NWC"9;
"S \NAC"
BN"6"92;
%"TAP"
"1","(2750,2500)","0","standard","I130";
;
CDS_LIB"standard"
BODY_TYPE"PLUMBING"
HDL_TAP"TRUE";
"B \NAC \NWC"8;
"S \NAC"
BN"3"103;
%"TAP"
"1","(2750,2450)","0","standard","I131";
;
CDS_LIB"standard"
BODY_TYPE"PLUMBING"
HDL_TAP"TRUE";
"B \NAC \NWC"8;
"S \NAC"
BN"2"102;
%"TAP"
"1","(2750,2400)","0","standard","I132";
;
CDS_LIB"standard"
BODY_TYPE"PLUMBING"
HDL_TAP"TRUE";
"B \NAC \NWC"8;
"S \NAC"
BN"1"101;
%"TAP"
"1","(2750,2550)","0","standard","I133";
;
CDS_LIB"standard"
BODY_TYPE"PLUMBING"
HDL_TAP"TRUE";
"B \NAC \NWC"8;
"S \NAC"
BN"4"104;
%"TAP"
"1","(2750,2600)","0","standard","I134";
;
CDS_LIB"standard"
BODY_TYPE"PLUMBING"
HDL_TAP"TRUE";
"B \NAC \NWC"8;
"S \NAC"
BN"5"105;
%"TAP"
"1","(2750,2650)","0","standard","I135";
;
CDS_LIB"standard"
BODY_TYPE"PLUMBING"
HDL_TAP"TRUE";
"B \NAC \NWC"8;
"S \NAC"
BN"6"106;
%"TAP"
"1","(2750,2700)","0","standard","I136";
;
CDS_LIB"standard"
BODY_TYPE"PLUMBING"
HDL_TAP"TRUE";
"B \NAC \NWC"8;
"S \NAC"
BN"7"107;
%"TAP"
"1","(2750,2750)","0","standard","I137";
;
CDS_LIB"standard"
BODY_TYPE"PLUMBING"
HDL_TAP"TRUE";
"B \NAC \NWC"8;
"S \NAC"
BN"8"108;
%"TAP"
"1","(2750,2800)","0","standard","I138";
;
CDS_LIB"standard"
BODY_TYPE"PLUMBING"
HDL_TAP"TRUE";
"B \NAC \NWC"8;
"S \NAC"
BN"9"109;
%"TAP"
"1","(2750,2950)","0","standard","I139";
;
CDS_LIB"standard"
BODY_TYPE"PLUMBING"
HDL_TAP"TRUE";
"B \NAC \NWC"3;
"S \NAC"
BN"0"142;
%"TAP"
"1","(2750,3000)","0","standard","I140";
;
CDS_LIB"standard"
BODY_TYPE"PLUMBING"
HDL_TAP"TRUE";
"B \NAC \NWC"3;
"S \NAC"
BN"1"143;
%"TAP"
"1","(2750,3100)","0","standard","I141";
;
CDS_LIB"standard"
BODY_TYPE"PLUMBING"
HDL_TAP"TRUE";
"B \NAC \NWC"3;
"S \NAC"
BN"3"145;
%"TAP"
"1","(2750,3050)","0","standard","I142";
;
CDS_LIB"standard"
BODY_TYPE"PLUMBING"
HDL_TAP"TRUE";
"B \NAC \NWC"3;
"S \NAC"
BN"2"144;
%"TAP"
"1","(2750,3150)","0","standard","I143";
;
CDS_LIB"standard"
BODY_TYPE"PLUMBING"
HDL_TAP"TRUE";
"B \NAC \NWC"3;
"S \NAC"
BN"4"146;
%"TAP"
"1","(2750,3200)","0","standard","I144";
;
CDS_LIB"standard"
BODY_TYPE"PLUMBING"
HDL_TAP"TRUE";
"B \NAC \NWC"3;
"S \NAC"
BN"5"147;
%"TAP"
"1","(2750,3250)","0","standard","I145";
;
CDS_LIB"standard"
BODY_TYPE"PLUMBING"
HDL_TAP"TRUE";
"B \NAC \NWC"3;
"S \NAC"
BN"6"148;
%"TAP"
"1","(2750,3350)","0","standard","I146";
;
CDS_LIB"standard"
BODY_TYPE"PLUMBING"
HDL_TAP"TRUE";
"B \NAC \NWC"3;
"S \NAC"
BN"8"150;
%"TAP"
"1","(2750,3300)","0","standard","I147";
;
CDS_LIB"standard"
BODY_TYPE"PLUMBING"
HDL_TAP"TRUE";
"B \NAC \NWC"3;
"S \NAC"
BN"7"149;
%"TAP"
"1","(2750,3500)","0","standard","I148";
;
CDS_LIB"standard"
BODY_TYPE"PLUMBING"
HDL_TAP"TRUE";
"B \NAC \NWC"4;
"S \NAC"
BN"0"132;
%"TAP"
"1","(2750,3400)","0","standard","I149";
;
CDS_LIB"standard"
BODY_TYPE"PLUMBING"
HDL_TAP"TRUE";
"B \NAC \NWC"3;
"S \NAC"
BN"9"151;
%"TAP"
"1","(2750,3650)","0","standard","I150";
;
CDS_LIB"standard"
BODY_TYPE"PLUMBING"
HDL_TAP"TRUE";
"B \NAC \NWC"4;
"S \NAC"
BN"3"135;
%"TAP"
"1","(2750,3600)","0","standard","I151";
;
CDS_LIB"standard"
BODY_TYPE"PLUMBING"
HDL_TAP"TRUE";
"B \NAC \NWC"4;
"S \NAC"
BN"2"134;
%"TAP"
"1","(2750,3550)","0","standard","I152";
;
CDS_LIB"standard"
BODY_TYPE"PLUMBING"
HDL_TAP"TRUE";
"B \NAC \NWC"4;
"S \NAC"
BN"1"133;
%"TAP"
"1","(2750,3750)","0","standard","I153";
;
CDS_LIB"standard"
BODY_TYPE"PLUMBING"
HDL_TAP"TRUE";
"B \NAC \NWC"4;
"S \NAC"
BN"5"137;
%"TAP"
"1","(2750,3700)","0","standard","I154";
;
CDS_LIB"standard"
BODY_TYPE"PLUMBING"
HDL_TAP"TRUE";
"B \NAC \NWC"4;
"S \NAC"
BN"4"136;
%"TAP"
"1","(2750,3850)","0","standard","I155";
;
CDS_LIB"standard"
BODY_TYPE"PLUMBING"
HDL_TAP"TRUE";
"B \NAC \NWC"4;
"S \NAC"
BN"7"139;
%"TAP"
"1","(2750,3900)","0","standard","I156";
;
CDS_LIB"standard"
BODY_TYPE"PLUMBING"
HDL_TAP"TRUE";
"B \NAC \NWC"4;
"S \NAC"
BN"8"140;
%"TAP"
"1","(2750,3800)","0","standard","I157";
;
CDS_LIB"standard"
BODY_TYPE"PLUMBING"
HDL_TAP"TRUE";
"B \NAC \NWC"4;
"S \NAC"
BN"6"138;
%"TAP"
"1","(2750,3950)","0","standard","I158";
;
CDS_LIB"standard"
BODY_TYPE"PLUMBING"
HDL_TAP"TRUE";
"B \NAC \NWC"4;
"S \NAC"
BN"9"141;
%"TAP"
"1","(-675,400)","2","standard","I17";
;
CDS_LIB"standard"
BODY_TYPE"PLUMBING"
HDL_TAP"TRUE";
"B \NAC \NWC"10;
"S \NAC"
BN"0"90;
%"TAP"
"1","(-675,350)","2","standard","I18";
;
CDS_LIB"standard"
BODY_TYPE"PLUMBING"
HDL_TAP"TRUE";
"B \NAC \NWC"9;
"S \NAC"
BN"7"91;
%"TAP"
"1","(-675,550)","2","standard","I19";
;
CDS_LIB"standard"
BODY_TYPE"PLUMBING"
HDL_TAP"TRUE";
"B \NAC \NWC"10;
"S \NAC"
BN"3"87;
%"TAP"
"1","(-675,500)","2","standard","I20";
;
CDS_LIB"standard"
BODY_TYPE"PLUMBING"
HDL_TAP"TRUE";
"B \NAC \NWC"10;
"S \NAC"
BN"2"88;
%"TAP"
"1","(-675,450)","2","standard","I21";
;
CDS_LIB"standard"
BODY_TYPE"PLUMBING"
HDL_TAP"TRUE";
"B \NAC \NWC"10;
"S \NAC"
BN"1"89;
%"TAP"
"1","(-675,650)","2","standard","I22";
;
CDS_LIB"standard"
BODY_TYPE"PLUMBING"
HDL_TAP"TRUE";
"B \NAC \NWC"10;
"S \NAC"
BN"5"85;
%"TAP"
"1","(-675,600)","2","standard","I23";
;
CDS_LIB"standard"
BODY_TYPE"PLUMBING"
HDL_TAP"TRUE";
"B \NAC \NWC"10;
"S \NAC"
BN"4"86;
%"TAP"
"1","(-675,800)","2","standard","I24";
;
CDS_LIB"standard"
BODY_TYPE"PLUMBING"
HDL_TAP"TRUE";
"B \NAC \NWC"10;
"S \NAC"
BN"8"82;
%"TAP"
"1","(-675,750)","2","standard","I25";
;
CDS_LIB"standard"
BODY_TYPE"PLUMBING"
HDL_TAP"TRUE";
"B \NAC \NWC"10;
"S \NAC"
BN"7"83;
%"TAP"
"1","(-675,700)","2","standard","I26";
;
CDS_LIB"standard"
BODY_TYPE"PLUMBING"
HDL_TAP"TRUE";
"B \NAC \NWC"10;
"S \NAC"
BN"6"84;
%"TAP"
"1","(-675,900)","2","standard","I27";
;
CDS_LIB"standard"
BODY_TYPE"PLUMBING"
HDL_TAP"TRUE";
"B \NAC \NWC"10;
"S \NAC"
BN"10"80;
%"TAP"
"1","(-675,850)","2","standard","I28";
;
CDS_LIB"standard"
BODY_TYPE"PLUMBING"
HDL_TAP"TRUE";
"B \NAC \NWC"10;
"S \NAC"
BN"9"81;
%"TAP"
"1","(-675,1050)","2","standard","I29";
;
CDS_LIB"standard"
BODY_TYPE"PLUMBING"
HDL_TAP"TRUE";
"B \NAC \NWC"10;
"S \NAC"
BN"13"77;
%"TAP"
"1","(-675,-250)","2","standard","I3";
;
CDS_LIB"standard"
BODY_TYPE"PLUMBING"
HDL_TAP"TRUE";
"B \NAC \NWC"14;
"S \NAC"
BN"0"16;
%"TAP"
"1","(-675,1000)","2","standard","I30";
;
CDS_LIB"standard"
BODY_TYPE"PLUMBING"
HDL_TAP"TRUE";
"B \NAC \NWC"10;
"S \NAC"
BN"12"78;
%"TAP"
"1","(-675,950)","2","standard","I31";
;
CDS_LIB"standard"
BODY_TYPE"PLUMBING"
HDL_TAP"TRUE";
"B \NAC \NWC"10;
"S \NAC"
BN"11"79;
%"TAP"
"1","(-675,1150)","2","standard","I32";
;
CDS_LIB"standard"
BODY_TYPE"PLUMBING"
HDL_TAP"TRUE";
"B \NAC \NWC"10;
"S \NAC"
BN"15"75;
%"TAP"
"1","(-675,1100)","2","standard","I33";
;
CDS_LIB"standard"
BODY_TYPE"PLUMBING"
HDL_TAP"TRUE";
"B \NAC \NWC"10;
"S \NAC"
BN"14"76;
%"TAP"
"1","(-675,1300)","2","standard","I34";
;
CDS_LIB"standard"
BODY_TYPE"PLUMBING"
HDL_TAP"TRUE";
"B \NAC \NWC"10;
"S \NAC"
BN"18"72;
%"TAP"
"1","(-675,1250)","2","standard","I35";
;
CDS_LIB"standard"
BODY_TYPE"PLUMBING"
HDL_TAP"TRUE";
"B \NAC \NWC"10;
"S \NAC"
BN"17"73;
%"TAP"
"1","(-675,1200)","2","standard","I36";
;
CDS_LIB"standard"
BODY_TYPE"PLUMBING"
HDL_TAP"TRUE";
"B \NAC \NWC"10;
"S \NAC"
BN"16"74;
%"TAP"
"1","(-675,1450)","2","standard","I37";
;
CDS_LIB"standard"
BODY_TYPE"PLUMBING"
HDL_TAP"TRUE";
"B \NAC \NWC"10;
"S \NAC"
BN"21"69;
%"TAP"
"1","(-675,1400)","2","standard","I38";
;
CDS_LIB"standard"
BODY_TYPE"PLUMBING"
HDL_TAP"TRUE";
"B \NAC \NWC"10;
"S \NAC"
BN"20"70;
%"TAP"
"1","(-675,1350)","2","standard","I39";
;
CDS_LIB"standard"
BODY_TYPE"PLUMBING"
HDL_TAP"TRUE";
"B \NAC \NWC"10;
"S \NAC"
BN"19"71;
%"TAP"
"1","(-675,0)","2","standard","I4";
;
CDS_LIB"standard"
BODY_TYPE"PLUMBING"
HDL_TAP"TRUE";
"B \NAC \NWC"9;
"S \NAC"
BN"0"98;
%"TAP"
"1","(-675,1550)","2","standard","I40";
;
CDS_LIB"standard"
BODY_TYPE"PLUMBING"
HDL_TAP"TRUE";
"B \NAC \NWC"10;
"S \NAC"
BN"23"67;
%"TAP"
"1","(-675,1500)","2","standard","I41";
;
CDS_LIB"standard"
BODY_TYPE"PLUMBING"
HDL_TAP"TRUE";
"B \NAC \NWC"10;
"S \NAC"
BN"22"68;
%"TAP"
"1","(-675,1700)","2","standard","I42";
;
CDS_LIB"standard"
BODY_TYPE"PLUMBING"
HDL_TAP"TRUE";
"B \NAC \NWC"10;
"S \NAC"
BN"26"64;
%"TAP"
"1","(-675,1650)","2","standard","I43";
;
CDS_LIB"standard"
BODY_TYPE"PLUMBING"
HDL_TAP"TRUE";
"B \NAC \NWC"10;
"S \NAC"
BN"25"65;
%"TAP"
"1","(-675,1600)","2","standard","I44";
;
CDS_LIB"standard"
BODY_TYPE"PLUMBING"
HDL_TAP"TRUE";
"B \NAC \NWC"10;
"S \NAC"
BN"24"66;
%"TAP"
"1","(-675,1800)","2","standard","I45";
;
CDS_LIB"standard"
BODY_TYPE"PLUMBING"
HDL_TAP"TRUE";
"B \NAC \NWC"10;
"S \NAC"
BN"28"62;
%"TAP"
"1","(-675,1750)","2","standard","I46";
;
CDS_LIB"standard"
BODY_TYPE"PLUMBING"
HDL_TAP"TRUE";
"B \NAC \NWC"10;
"S \NAC"
BN"27"63;
%"TAP"
"1","(-675,1900)","2","standard","I47";
;
CDS_LIB"standard"
BODY_TYPE"PLUMBING"
HDL_TAP"TRUE";
"B \NAC \NWC"10;
"S \NAC"
BN"30"60;
%"TAP"
"1","(-675,1950)","2","standard","I48";
;
CDS_LIB"standard"
BODY_TYPE"PLUMBING"
HDL_TAP"TRUE";
"B \NAC \NWC"10;
"S \NAC"
BN"31"59;
%"TAP"
"1","(-675,1850)","2","standard","I49";
;
CDS_LIB"standard"
BODY_TYPE"PLUMBING"
HDL_TAP"TRUE";
"B \NAC \NWC"10;
"S \NAC"
BN"29"61;
%"TAP"
"1","(-675,-200)","2","standard","I5";
;
CDS_LIB"standard"
BODY_TYPE"PLUMBING"
HDL_TAP"TRUE";
"B \NAC \NWC"14;
"S \NAC"
BN"1"15;
%"TAP"
"1","(-675,2050)","2","standard","I50";
;
CDS_LIB"standard"
BODY_TYPE"PLUMBING"
HDL_TAP"TRUE";
"B \NAC \NWC"11;
"S \NAC"
BN"1"57;
%"TAP"
"1","(-675,2000)","2","standard","I51";
;
CDS_LIB"standard"
BODY_TYPE"PLUMBING"
HDL_TAP"TRUE";
"B \NAC \NWC"11;
"S \NAC"
BN"0"58;
%"TAP"
"1","(-675,2200)","2","standard","I52";
;
CDS_LIB"standard"
BODY_TYPE"PLUMBING"
HDL_TAP"TRUE";
"B \NAC \NWC"11;
"S \NAC"
BN"4"54;
%"TAP"
"1","(-675,2150)","2","standard","I53";
;
CDS_LIB"standard"
BODY_TYPE"PLUMBING"
HDL_TAP"TRUE";
"B \NAC \NWC"11;
"S \NAC"
BN"3"55;
%"TAP"
"1","(-675,2100)","2","standard","I54";
;
CDS_LIB"standard"
BODY_TYPE"PLUMBING"
HDL_TAP"TRUE";
"B \NAC \NWC"11;
"S \NAC"
BN"2"56;
%"TAP"
"1","(-675,2300)","2","standard","I55";
;
CDS_LIB"standard"
BODY_TYPE"PLUMBING"
HDL_TAP"TRUE";
"B \NAC \NWC"11;
"S \NAC"
BN"6"52;
%"TAP"
"1","(-675,2250)","2","standard","I56";
;
CDS_LIB"standard"
BODY_TYPE"PLUMBING"
HDL_TAP"TRUE";
"B \NAC \NWC"11;
"S \NAC"
BN"5"53;
%"TAP"
"1","(-675,2450)","2","standard","I58";
;
CDS_LIB"standard"
BODY_TYPE"PLUMBING"
HDL_TAP"TRUE";
"B \NAC \NWC"12;
"S \NAC"
BN"1"49;
%"TAP"
"1","(-675,2400)","2","standard","I59";
;
CDS_LIB"standard"
BODY_TYPE"PLUMBING"
HDL_TAP"TRUE";
"B \NAC \NWC"12;
"S \NAC"
BN"0"50;
%"TAP"
"1","(-675,-100)","2","standard","I6";
;
CDS_LIB"standard"
BODY_TYPE"PLUMBING"
HDL_TAP"TRUE";
"B \NAC \NWC"13;
"S \NAC"
BN"1"17;
%"TAP"
"1","(-675,2350)","2","standard","I60";
;
CDS_LIB"standard"
BODY_TYPE"PLUMBING"
HDL_TAP"TRUE";
"B \NAC \NWC"11;
"S \NAC"
BN"7"51;
%"TAP"
"1","(-675,2600)","2","standard","I61";
;
CDS_LIB"standard"
BODY_TYPE"PLUMBING"
HDL_TAP"TRUE";
"B \NAC \NWC"12;
"S \NAC"
BN"4"46;
%"TAP"
"1","(-675,2550)","2","standard","I62";
;
CDS_LIB"standard"
BODY_TYPE"PLUMBING"
HDL_TAP"TRUE";
"B \NAC \NWC"12;
"S \NAC"
BN"3"47;
%"TAP"
"1","(-675,2500)","2","standard","I63";
;
CDS_LIB"standard"
BODY_TYPE"PLUMBING"
HDL_TAP"TRUE";
"B \NAC \NWC"12;
"S \NAC"
BN"2"48;
%"TAP"
"1","(-675,2700)","2","standard","I64";
;
CDS_LIB"standard"
BODY_TYPE"PLUMBING"
HDL_TAP"TRUE";
"B \NAC \NWC"12;
"S \NAC"
BN"6"44;
%"TAP"
"1","(-675,2650)","2","standard","I65";
;
CDS_LIB"standard"
BODY_TYPE"PLUMBING"
HDL_TAP"TRUE";
"B \NAC \NWC"12;
"S \NAC"
BN"5"45;
%"TAP"
"1","(-675,2850)","2","standard","I66";
;
CDS_LIB"standard"
BODY_TYPE"PLUMBING"
HDL_TAP"TRUE";
"B \NAC \NWC"12;
"S \NAC"
BN"9"41;
%"TAP"
"1","(-675,2800)","2","standard","I67";
;
CDS_LIB"standard"
BODY_TYPE"PLUMBING"
HDL_TAP"TRUE";
"B \NAC \NWC"12;
"S \NAC"
BN"8"42;
%"TAP"
"1","(-675,2750)","2","standard","I68";
;
CDS_LIB"standard"
BODY_TYPE"PLUMBING"
HDL_TAP"TRUE";
"B \NAC \NWC"12;
"S \NAC"
BN"7"43;
%"TAP"
"1","(-675,2950)","2","standard","I69";
;
CDS_LIB"standard"
BODY_TYPE"PLUMBING"
HDL_TAP"TRUE";
"B \NAC \NWC"12;
"S \NAC"
BN"11"39;
%"TAP"
"1","(-675,-150)","2","standard","I7";
;
CDS_LIB"standard"
BODY_TYPE"PLUMBING"
HDL_TAP"TRUE";
"B \NAC \NWC"13;
"S \NAC"
BN"0"18;
%"TAP"
"1","(-675,2900)","2","standard","I70";
;
CDS_LIB"standard"
BODY_TYPE"PLUMBING"
HDL_TAP"TRUE";
"B \NAC \NWC"12;
"S \NAC"
BN"10"40;
%"TAP"
"1","(-675,3100)","2","standard","I71";
;
CDS_LIB"standard"
BODY_TYPE"PLUMBING"
HDL_TAP"TRUE";
"B \NAC \NWC"12;
"S \NAC"
BN"14"36;
%"TAP"
"1","(-675,3050)","2","standard","I72";
;
CDS_LIB"standard"
BODY_TYPE"PLUMBING"
HDL_TAP"TRUE";
"B \NAC \NWC"12;
"S \NAC"
BN"13"37;
%"TAP"
"1","(-675,3000)","2","standard","I73";
;
CDS_LIB"standard"
BODY_TYPE"PLUMBING"
HDL_TAP"TRUE";
"B \NAC \NWC"12;
"S \NAC"
BN"12"38;
%"TAP"
"1","(-675,3200)","2","standard","I74";
;
CDS_LIB"standard"
BODY_TYPE"PLUMBING"
HDL_TAP"TRUE";
"B \NAC \NWC"12;
"S \NAC"
BN"16"34;
%"TAP"
"1","(-675,3150)","2","standard","I75";
;
CDS_LIB"standard"
BODY_TYPE"PLUMBING"
HDL_TAP"TRUE";
"B \NAC \NWC"12;
"S \NAC"
BN"15"35;
%"TAP"
"1","(-675,3350)","2","standard","I76";
;
CDS_LIB"standard"
BODY_TYPE"PLUMBING"
HDL_TAP"TRUE";
"B \NAC \NWC"12;
"S \NAC"
BN"19"31;
%"TAP"
"1","(-675,3300)","2","standard","I77";
;
CDS_LIB"standard"
BODY_TYPE"PLUMBING"
HDL_TAP"TRUE";
"B \NAC \NWC"12;
"S \NAC"
BN"18"32;
%"TAP"
"1","(-675,3250)","2","standard","I78";
;
CDS_LIB"standard"
BODY_TYPE"PLUMBING"
HDL_TAP"TRUE";
"B \NAC \NWC"12;
"S \NAC"
BN"17"33;
%"TAP"
"1","(-675,3450)","2","standard","I79";
;
CDS_LIB"standard"
BODY_TYPE"PLUMBING"
HDL_TAP"TRUE";
"B \NAC \NWC"12;
"S \NAC"
BN"21"29;
%"TAP"
"1","(-675,100)","2","standard","I8";
;
CDS_LIB"standard"
BODY_TYPE"PLUMBING"
HDL_TAP"TRUE";
"B \NAC \NWC"9;
"S \NAC"
BN"2"96;
%"TAP"
"1","(-675,3400)","2","standard","I80";
;
CDS_LIB"standard"
BODY_TYPE"PLUMBING"
HDL_TAP"TRUE";
"B \NAC \NWC"12;
"S \NAC"
BN"20"30;
%"TAP"
"1","(-675,3500)","2","standard","I81";
;
CDS_LIB"standard"
BODY_TYPE"PLUMBING"
HDL_TAP"TRUE";
"B \NAC \NWC"12;
"S \NAC"
BN"22"28;
%"TAP"
"1","(-675,3600)","2","standard","I82";
;
CDS_LIB"standard"
BODY_TYPE"PLUMBING"
HDL_TAP"TRUE";
"B \NAC \NWC"12;
"S \NAC"
BN"24"26;
%"TAP"
"1","(-675,3550)","2","standard","I83";
;
CDS_LIB"standard"
BODY_TYPE"PLUMBING"
HDL_TAP"TRUE";
"B \NAC \NWC"12;
"S \NAC"
BN"23"27;
%"TAP"
"1","(-675,3750)","2","standard","I84";
;
CDS_LIB"standard"
BODY_TYPE"PLUMBING"
HDL_TAP"TRUE";
"B \NAC \NWC"12;
"S \NAC"
BN"27"23;
%"TAP"
"1","(-675,3700)","2","standard","I85";
;
CDS_LIB"standard"
BODY_TYPE"PLUMBING"
HDL_TAP"TRUE";
"B \NAC \NWC"12;
"S \NAC"
BN"26"24;
%"TAP"
"1","(-675,3650)","2","standard","I86";
;
CDS_LIB"standard"
BODY_TYPE"PLUMBING"
HDL_TAP"TRUE";
"B \NAC \NWC"12;
"S \NAC"
BN"25"25;
%"TAP"
"1","(-675,3850)","2","standard","I87";
;
CDS_LIB"standard"
BODY_TYPE"PLUMBING"
HDL_TAP"TRUE";
"B \NAC \NWC"12;
"S \NAC"
BN"29"21;
%"TAP"
"1","(-675,3800)","2","standard","I88";
;
CDS_LIB"standard"
BODY_TYPE"PLUMBING"
HDL_TAP"TRUE";
"B \NAC \NWC"12;
"S \NAC"
BN"28"22;
%"TAP"
"1","(-675,3950)","2","standard","I89";
;
CDS_LIB"standard"
BODY_TYPE"PLUMBING"
HDL_TAP"TRUE";
"B \NAC \NWC"12;
"S \NAC"
BN"31"19;
%"TAP"
"1","(-675,150)","2","standard","I9";
;
CDS_LIB"standard"
BODY_TYPE"PLUMBING"
HDL_TAP"TRUE";
"B \NAC \NWC"9;
"S \NAC"
BN"3"95;
%"TAP"
"1","(-675,3900)","2","standard","I90";
;
CDS_LIB"standard"
BODY_TYPE"PLUMBING"
HDL_TAP"TRUE";
"B \NAC \NWC"12;
"S \NAC"
BN"30"20;
%"SOCKET4677_AZIF0045P001C01CS"
"10","(1050,1850)","0","pure_quanta","I91";
;
PART_NUMBER"DGA^7000023"
PART_TYPE"SMLF"
MATERIAL"IO"
VALUE"SOCKET4677_AZIF0045-P001C01CS"
$LOCATION"U1"
CDS_LIB"pure_quanta"
NEEDS_NO_SIZE"TRUE"
CDS_LMAN_SYM_OUTLINE"-1100,2250,1050,-2250"
CDS_LOCATION"U1"
$SEC"10"
CDS_SEC"10";
"DDR2_SB_PAR"
$PN"AA39"99;
"DDR2_SB_ECC0"
$PN"T32"98;
"DDR2_SB_ECC1"
$PN"U31"97;
"DDR2_SB_ECC2"
$PN"Y32"96;
"DDR2_SB_ECC3"
$PN"W31"95;
"DDR2_SB_ECC4"
$PN"U35"94;
"DDR2_SB_ECC5"
$PN"T34"93;
"DDR2_SB_ECC6"
$PN"W35"92;
"DDR2_SB_ECC7"
$PN"Y34"91;
"DDR2_SB_DQS_DP0"
$PN"AD36"100;
"DDR2_SB_DQS_DP1"
$PN"AD30"101;
"DDR2_SB_DQS_DP2"
$PN"U21"102;
"DDR2_SB_DQS_DP3"
$PN"AD18"103;
"DDR2_SB_DQS_DP4"
$PN"AA33"104;
"DDR2_SB_DQS_DP5"
$PN"AH36"105;
"DDR2_SB_DQS_DP6"
$PN"AH30"106;
"DDR2_SB_DQS_DP7"
$PN"AA21"107;
"DDR2_SB_DQS_DP8"
$PN"AH18"108;
"DDR2_SB_DQS_DP9"
$PN"U33"109;
"DDR2_SB_DQS_DN0 \B"
$PN"AB36"110;
"DDR2_SB_DQS_DN1 \B"
$PN"AB30"111;
"DDR2_SB_DQS_DN2 \B"
$PN"R21"112;
"DDR2_SB_DQS_DN3 \B"
$PN"AB18"113;
"DDR2_SB_DQS_DN4 \B"
$PN"W33"114;
"DDR2_SB_DQS_DN5 \B"
$PN"AF36"115;
"DDR2_SB_DQS_DN6 \B"
$PN"AF30"116;
"DDR2_SB_DQS_DN7 \B"
$PN"W21"117;
"DDR2_SB_DQS_DN8 \B"
$PN"AF18"118;
"DDR2_SB_DQS_DN9 \B"
$PN"R33"119;
"DDR2_SB_DQ0"
$PN"AD38"90;
"DDR2_SB_DQ1"
$PN"AC37"89;
"DDR2_SB_DQ2"
$PN"AF38"88;
"DDR2_SB_DQ3"
$PN"AG37"87;
"DDR2_SB_DQ4"
$PN"AC35"86;
"DDR2_SB_DQ5"
$PN"AD34"85;
"DDR2_SB_DQ6"
$PN"AG35"84;
"DDR2_SB_DQ7"
$PN"AF34"83;
"DDR2_SB_DQ8"
$PN"AD32"82;
"DDR2_SB_DQ9"
$PN"AC31"81;
"DDR2_SB_DQ10"
$PN"AF32"80;
"DDR2_SB_DQ11"
$PN"AG31"79;
"DDR2_SB_DQ12"
$PN"AC29"78;
"DDR2_SB_DQ13"
$PN"AD28"77;
"DDR2_SB_DQ14"
$PN"AG29"76;
"DDR2_SB_DQ15"
$PN"AF28"75;
"DDR2_SB_DQ16"
$PN"U23"74;
"DDR2_SB_DQ17"
$PN"T22"73;
"DDR2_SB_DQ18"
$PN"W23"72;
"DDR2_SB_DQ19"
$PN"Y22"71;
"DDR2_SB_DQ20"
$PN"T20"70;
"DDR2_SB_DQ21"
$PN"U19"69;
"DDR2_SB_DQ22"
$PN"Y20"68;
"DDR2_SB_DQ23"
$PN"W19"67;
"DDR2_SB_DQ24"
$PN"AD20"66;
"DDR2_SB_DQ25"
$PN"AC19"65;
"DDR2_SB_DQ26"
$PN"AF20"64;
"DDR2_SB_DQ27"
$PN"AG19"63;
"DDR2_SB_DQ28"
$PN"AA17"62;
"DDR2_SB_DQ29"
$PN"AG17"61;
"DDR2_SB_DQ30"
$PN"AC17"60;
"DDR2_SB_DQ31"
$PN"AJ17"59;
"DDR2_SB_CS_N0 \B"
$PN"T38"120;
"DDR2_SB_CS_N1 \B"
$PN"U37"121;
"DDR2_SB_CS_N2 \B"
$PN"Y38"122;
"DDR2_SB_CS_N3 \B"
$PN"W37"123;
"DDR2_SB_CA0"
$PN"W48"124;
"DDR2_SB_CA1"
$PN"Y47"125;
"DDR2_SB_CA2"
$PN"U41"126;
"DDR2_SB_CA3"
$PN"W41"127;
"DDR2_SB_CA4"
$PN"T40"128;
"DDR2_SB_CA5"
$PN"Y40"129;
"DDR2_SB_CA6"
$PN"R39"130;
"DDR2_SA_PAR"
$PN"T47"131;
"DDR2_SA_ECC0"
$PN"AD57"58;
"DDR2_SA_ECC1"
$PN"AC56"57;
"DDR2_SA_ECC2"
$PN"AF57"56;
"DDR2_SA_ECC3"
$PN"AG56"55;
"DDR2_SA_ECC4"
$PN"AC54"54;
"DDR2_SA_ECC5"
$PN"AD53"53;
"DDR2_SA_ECC6"
$PN"AG54"52;
"DDR2_SA_ECC7"
$PN"AF53"51;
"DDR2_SA_DQS_DP0"
$PN"U76"132;
"DDR2_SA_DQS_DP1"
$PN"AD67"133;
"DDR2_SA_DQS_DP2"
$PN"U64"134;
"DDR2_SA_DQS_DP3"
$PN"AD61"135;
"DDR2_SA_DQS_DP4"
$PN"AB55"136;
"DDR2_SA_DQS_DP5"
$PN"AA76"137;
"DDR2_SA_DQS_DP6"
$PN"AF67"138;
"DDR2_SA_DQS_DP7"
$PN"W64"139;
"DDR2_SA_DQS_DP8"
$PN"AH61"140;
"DDR2_SA_DQS_DP9"
$PN"AF55"141;
"DDR2_SA_DQS_DN0 \B"
$PN"R76"142;
"DDR2_SA_DQS_DN1 \B"
$PN"AB67"143;
"DDR2_SA_DQS_DN2 \B"
$PN"R64"144;
"DDR2_SA_DQS_DN3 \B"
$PN"AB61"145;
"DDR2_SA_DQS_DN4 \B"
$PN"AD55"146;
"DDR2_SA_DQS_DN5 \B"
$PN"W76"147;
"DDR2_SA_DQS_DN6 \B"
$PN"AH67"148;
"DDR2_SA_DQS_DN7 \B"
$PN"AA64"149;
"DDR2_SA_DQS_DN8 \B"
$PN"AF61"150;
"DDR2_SA_DQS_DN9 \B"
$PN"AH55"151;
"DDR2_SA_DQ0"
$PN"U78"50;
"DDR2_SA_DQ1"
$PN"T77"49;
"DDR2_SA_DQ2"
$PN"W78"48;
"DDR2_SA_DQ3"
$PN"Y77"47;
"DDR2_SA_DQ4"
$PN"T75"46;
"DDR2_SA_DQ5"
$PN"U74"45;
"DDR2_SA_DQ6"
$PN"Y75"44;
"DDR2_SA_DQ7"
$PN"W74"43;
"DDR2_SA_DQ8"
$PN"AD69"42;
"DDR2_SA_DQ9"
$PN"AC68"41;
"DDR2_SA_DQ10"
$PN"AF69"40;
"DDR2_SA_DQ11"
$PN"AG68"39;
"DDR2_SA_DQ12"
$PN"AC66"38;
"DDR2_SA_DQ13"
$PN"AD65"37;
"DDR2_SA_DQ14"
$PN"AG66"36;
"DDR2_SA_DQ15"
$PN"AF65"35;
"DDR2_SA_DQ16"
$PN"U66"34;
"DDR2_SA_DQ17"
$PN"T65"33;
"DDR2_SA_DQ18"
$PN"W66"32;
"DDR2_SA_DQ19"
$PN"Y65"31;
"DDR2_SA_DQ20"
$PN"T63"30;
"DDR2_SA_DQ21"
$PN"U62"29;
"DDR2_SA_DQ22"
$PN"Y63"28;
"DDR2_SA_DQ23"
$PN"W62"27;
"DDR2_SA_DQ24"
$PN"AD63"26;
"DDR2_SA_DQ25"
$PN"AC62"25;
"DDR2_SA_DQ26"
$PN"AF63"24;
"DDR2_SA_DQ27"
$PN"AG62"23;
"DDR2_SA_DQ28"
$PN"AC60"22;
"DDR2_SA_DQ29"
$PN"AD59"21;
"DDR2_SA_DQ30"
$PN"AG60"20;
"DDR2_SA_DQ31"
$PN"AF59"19;
"DDR2_SA_CS_N0 \B"
$PN"U54"152;
"DDR2_SA_CS_N1 \B"
$PN"T53"153;
"DDR2_SA_CS_N2 \B"
$PN"W54"154;
"DDR2_SA_CS_N3 \B"
$PN"Y53"155;
"DDR2_SA_CA0"
$PN"R52"156;
"DDR2_SA_CA1"
$PN"AA52"157;
"DDR2_SA_CA2"
$PN"T51"158;
"DDR2_SA_CA3"
$PN"Y51"159;
"DDR2_SA_CA4"
$PN"U50"160;
"DDR2_SA_CA5"
$PN"W50"161;
"DDR2_SA_CA6"
$PN"U48"162;
"DDR2_CLK_DP0"
$PN"AD49"18;
"DDR2_CLK_DP1"
$PN"AH49"17;
"DDR2_CLK_DN0 \B"
$PN"AB49"16;
"DDR2_CLK_DN1 \B"
$PN"AF49"15;
"DDR2_B_RSP0"
$PN"AG48"163;
"DDR2_B_RSP1"
$PN"AF47"164;
"DDR2_A_RSP0"
$PN"AC48"165;
"DDR2_A_RSP1"
$PN"AD47"166;
"DDR2_ALERT_N \B"
$PN"AT47"167;
%"TAP"
"1","(2750,300)","0","standard","I92";
;
CDS_LIB"standard"
BODY_TYPE"PLUMBING"
HDL_TAP"TRUE";
"B \NAC \NWC"6;
"S \NAC"
BN"2"122;
%"TAP"
"1","(2750,250)","0","standard","I93";
;
CDS_LIB"standard"
BODY_TYPE"PLUMBING"
HDL_TAP"TRUE";
"B \NAC \NWC"6;
"S \NAC"
BN"1"121;
%"TAP"
"1","(2750,200)","0","standard","I94";
;
CDS_LIB"standard"
BODY_TYPE"PLUMBING"
HDL_TAP"TRUE";
"B \NAC \NWC"6;
"S \NAC"
BN"0"120;
END.
